(kicad_pcb
	(version 20260206)
	(generator "pcbnew")
	(generator_version "10.0")
	(general
		(thickness 1.6)
		(legacy_teardrops no)
	)
	(paper "A4")
	(title_block
		(title "Wiwynn_Tioga_Pass_MB.brd")
		(comment 1 "Tioga Pass / footprints 3350-3356 of 4770")
	)
	(layers
		(0 "F.Cu" signal "TOP")
		(4 "In1.Cu" signal "L2GND")
		(6 "In2.Cu" signal "L3")
		(8 "In3.Cu" signal "L4GND")
		(10 "In4.Cu" signal "L5")
		(12 "In5.Cu" signal "L6GND")
		(14 "In6.Cu" signal "L7VCC")
		(16 "In7.Cu" signal "L8VCC")
		(18 "In8.Cu" signal "L9GND")
		(20 "In9.Cu" signal "L10")
		(22 "In10.Cu" signal "L11GND")
		(24 "In11.Cu" signal "L12")
		(26 "In12.Cu" signal "L13GND")
		(2 "B.Cu" signal "BOTTOM")
		(9 "F.Adhes" user "F.Adhesive")
		(11 "B.Adhes" user "B.Adhesive")
		(13 "F.Paste" user "Package Geometry/Pastemask Top")
		(15 "B.Paste" user "Package Geometry/Pastemask Bottom")
		(5 "F.SilkS" user "Ref Des/Silkscreen Top")
		(7 "B.SilkS" user "Ref Des/Silkscreen Bottom")
		(1 "F.Mask" user "Board Geometry/Soldermask Top")
		(3 "B.Mask" user "Board Geometry/Soldermask Bottom")
		(17 "Dwgs.User" user "User.Drawings")
		(19 "Cmts.User" user "User.Comments")
		(21 "Eco1.User" user "User.Eco1")
		(23 "Eco2.User" user "User.Eco2")
		(25 "Edge.Cuts" user "Board Geometry/Outline")
		(27 "Margin" user)
		(31 "F.CrtYd" user "Package Geometry/Place Bound Top")
		(29 "B.CrtYd" user "Package Geometry/Place Bound Bottom")
		(35 "F.Fab" user "Ref Des/Assembly Top")
		(33 "B.Fab" user "Ref Des/Assembly Bottom")
	)
	(footprint ""
		(layer "B.Cu")
		(at -4.36626 -120.60936)
		(property "Reference" "C9M7"
			(at 0 0 0)
			(layer "B.SilkS")
			(hide yes)
			(effects
				(font
					(size 1.27 1.27)
				)
				(justify mirror)
			)
		)
		(property "Value" ""
			(at 0 0 0)
			(layer "B.Fab")
			(effects
				(font
					(size 1.27 1.27)
				)
				(justify mirror)
			)
		)
		(duplicate_pad_numbers_are_jumpers no)
		(fp_rect
			(start -0.3048 0.9906)
			(end 0.3048 -0.1016)
			(stroke
				(width 0)
				(type default)
			)
			(fill no)
			(layer "B.CrtYd")
		)
		(fp_line
			(start -0.3048 -0.1016)
			(end 0.3048 -0.1016)
			(stroke
				(width 0.1)
				(type default)
			)
			(layer "B.Fab")
		)
		(fp_line
			(start -0.3048 0.9906)
			(end -0.3048 -0.1016)
			(stroke
				(width 0.1)
				(type default)
			)
			(layer "B.Fab")
		)
		(fp_line
			(start 0.3048 -0.1016)
			(end 0.3048 0.9906)
			(stroke
				(width 0.1)
				(type default)
			)
			(layer "B.Fab")
		)
		(fp_line
			(start 0.3048 0.9906)
			(end -0.3048 0.9906)
			(stroke
				(width 0.1)
				(type default)
			)
			(layer "B.Fab")
		)
		(pad "1" smd rect
			(at 0 0 180)
			(size 0.508 0.508)
			(layers "B.Cu" "B.Mask" "B.Paste")
			(net "P3V3_STBY")
		)
		(pad "2" smd rect
			(at 0 0.889 180)
			(size 0.508 0.508)
			(layers "B.Cu" "B.Mask" "B.Paste")
			(net "GND")
		)
		(zone
			(layer "B.Cu")
			(hatch none 0.5)
			(connect_pads
				(clearance 0)
			)
			(min_thickness 0.25)
			(keepout
				(tracks allowed)
				(vias not_allowed)
				(pads allowed)
				(copperpour not_allowed)
				(footprints allowed)
			)
			(placement
				(enabled no)
				(sheetname "")
			)
			(fill
				(thermal_gap 0.5)
				(thermal_bridge_width 0.5)
				(island_removal_mode 0)
			)
			(polygon
				(pts
					(xy -4.62026 -119.97436) (xy -4.11226 -119.97436) (xy -4.11226 -120.35536) (xy -4.62026 -120.35536)
				)
			)
		)
		(zone
			(layer "B.Cu")
			(hatch none 0.5)
			(connect_pads
				(clearance 0)
			)
			(min_thickness 0.25)
			(keepout
				(tracks not_allowed)
				(vias allowed)
				(pads allowed)
				(copperpour not_allowed)
				(footprints allowed)
			)
			(placement
				(enabled no)
				(sheetname "")
			)
			(fill
				(thermal_gap 0.5)
				(thermal_bridge_width 0.5)
				(island_removal_mode 0)
			)
			(polygon
				(pts
					(xy -4.62026 -119.97436) (xy -4.11226 -119.97436) (xy -4.11226 -120.35536) (xy -4.62026 -120.35536)
				)
			)
		)
	)
	(footprint ""
		(layer "B.Cu")
		(at 17.653 -42.291 -90)
		(property "Reference" "R9R12"
			(at 0 0 90)
			(layer "B.SilkS")
			(hide yes)
			(effects
				(font
					(size 1.27 1.27)
				)
				(justify mirror)
			)
		)
		(property "Value" ""
			(at 0 0 90)
			(layer "B.Fab")
			(effects
				(font
					(size 1.27 1.27)
				)
				(justify mirror)
			)
		)
		(duplicate_pad_numbers_are_jumpers no)
		(fp_poly
			(pts
				(xy 0.2794 -0.1016) (xy -0.2794 -0.1016) (xy -0.2794 0.9906) (xy 0.2794 0.9906)
			)
			(stroke
				(width 0)
				(type default)
			)
			(fill no)
			(layer "B.CrtYd")
		)
		(fp_line
			(start -0.2794 0.9906)
			(end -0.2794 -0.1016)
			(stroke
				(width 0.1)
				(type default)
			)
			(layer "B.Fab")
		)
		(fp_line
			(start 0.2794 0.9906)
			(end -0.2794 0.9906)
			(stroke
				(width 0.1)
				(type default)
			)
			(layer "B.Fab")
		)
		(fp_line
			(start -0.2794 -0.1016)
			(end 0.2794 -0.1016)
			(stroke
				(width 0.1)
				(type default)
			)
			(layer "B.Fab")
		)
		(fp_line
			(start 0.2794 -0.1016)
			(end 0.2794 0.9906)
			(stroke
				(width 0.1)
				(type default)
			)
			(layer "B.Fab")
		)
		(pad "1" smd rect
			(at 0 0 90)
			(size 0.508 0.508)
			(layers "B.Cu" "B.Mask" "B.Paste")
			(net "FAN_TACH2")
		)
		(pad "2" smd rect
			(at 0 0.889 90)
			(size 0.508 0.508)
			(layers "B.Cu" "B.Mask" "B.Paste")
			(net "FAN_TACH2_R")
		)
		(zone
			(layer "B.Cu")
			(hatch none 0.5)
			(connect_pads
				(clearance 0)
			)
			(min_thickness 0.25)
			(keepout
				(tracks not_allowed)
				(vias allowed)
				(pads allowed)
				(copperpour not_allowed)
				(footprints allowed)
			)
			(placement
				(enabled no)
				(sheetname "")
			)
			(fill
				(thermal_gap 0.5)
				(thermal_bridge_width 0.5)
				(island_removal_mode 0)
			)
			(polygon
				(pts
					(xy 17.018 -42.037) (xy 17.018 -42.545) (xy 17.399 -42.545) (xy 17.399 -42.037)
				)
			)
		)
		(zone
			(layer "B.Cu")
			(hatch none 0.5)
			(connect_pads
				(clearance 0)
			)
			(min_thickness 0.25)
			(keepout
				(tracks allowed)
				(vias not_allowed)
				(pads allowed)
				(copperpour not_allowed)
				(footprints allowed)
			)
			(placement
				(enabled no)
				(sheetname "")
			)
			(fill
				(thermal_gap 0.5)
				(thermal_bridge_width 0.5)
				(island_removal_mode 0)
			)
			(polygon
				(pts
					(xy 17.399 -42.037) (xy 17.399 -42.545) (xy 17.018 -42.545) (xy 17.018 -42.037)
				)
			)
		)
	)
	(footprint ""
		(layer "B.Cu")
		(at 271.731486 -79.60614 180)
		(property "Reference" "C5P12"
			(at 0 0 0)
			(layer "B.SilkS")
			(hide yes)
			(effects
				(font
					(size 1.27 1.27)
				)
				(justify mirror)
			)
		)
		(property "Value" ""
			(at 0 0 0)
			(layer "B.Fab")
			(effects
				(font
					(size 1.27 1.27)
				)
				(justify mirror)
			)
		)
		(duplicate_pad_numbers_are_jumpers no)
		(fp_poly
			(pts
				(xy 0.7239 -0.2159) (xy -0.7239 -0.2159) (xy -0.7239 1.9939) (xy 0.7239 1.9939)
			)
			(stroke
				(width 0)
				(type default)
			)
			(fill no)
			(layer "B.CrtYd")
		)
		(fp_line
			(start 0.7239 1.9939)
			(end -0.7239 1.9939)
			(stroke
				(width 0.1)
				(type default)
			)
			(layer "B.Fab")
		)
		(fp_line
			(start 0.7239 -0.2159)
			(end 0.7239 1.9939)
			(stroke
				(width 0.1)
				(type default)
			)
			(layer "B.Fab")
		)
		(fp_line
			(start -0.7239 1.9939)
			(end -0.7239 -0.2159)
			(stroke
				(width 0.1)
				(type default)
			)
			(layer "B.Fab")
		)
		(fp_line
			(start -0.7239 -0.2159)
			(end 0.7239 -0.2159)
			(stroke
				(width 0.1)
				(type default)
			)
			(layer "B.Fab")
		)
		(pad "1" smd rect
			(at 0 0)
			(size 1.27 1.016)
			(layers "B.Cu" "B.Mask" "B.Paste")
			(net "PVCCMCP_CPU0")
		)
		(pad "2" smd rect
			(at 0 1.778)
			(size 1.27 1.016)
			(layers "B.Cu" "B.Mask" "B.Paste")
			(net "GND")
		)
		(zone
			(layer "B.Cu")
			(hatch none 0.5)
			(connect_pads
				(clearance 0)
			)
			(min_thickness 0.25)
			(keepout
				(tracks not_allowed)
				(vias allowed)
				(pads allowed)
				(copperpour not_allowed)
				(footprints allowed)
			)
			(placement
				(enabled no)
				(sheetname "")
			)
			(fill
				(thermal_gap 0.5)
				(thermal_bridge_width 0.5)
				(island_removal_mode 0)
			)
			(polygon
				(pts
					(xy 271.096486 -80.11414) (xy 272.366486 -80.11414) (xy 272.366486 -80.87614) (xy 271.096486 -80.87614)
				)
			)
		)
	)
	(footprint ""
		(layer "B.Cu")
		(at 32.3342 -54.5084 90)
		(property "Reference" "R9R2"
			(at 0 0 90)
			(layer "B.SilkS")
			(hide yes)
			(effects
				(font
					(size 1.27 1.27)
				)
				(justify mirror)
			)
		)
		(property "Value" ""
			(at 0 0 90)
			(layer "B.Fab")
			(effects
				(font
					(size 1.27 1.27)
				)
				(justify mirror)
			)
		)
		(duplicate_pad_numbers_are_jumpers no)
		(fp_poly
			(pts
				(xy 0.2794 -0.1016) (xy -0.2794 -0.1016) (xy -0.2794 0.9906) (xy 0.2794 0.9906)
			)
			(stroke
				(width 0)
				(type default)
			)
			(fill no)
			(layer "B.CrtYd")
		)
		(fp_line
			(start 0.2794 -0.1016)
			(end 0.2794 0.9906)
			(stroke
				(width 0.1)
				(type default)
			)
			(layer "B.Fab")
		)
		(fp_line
			(start -0.2794 -0.1016)
			(end 0.2794 -0.1016)
			(stroke
				(width 0.1)
				(type default)
			)
			(layer "B.Fab")
		)
		(fp_line
			(start 0.2794 0.9906)
			(end -0.2794 0.9906)
			(stroke
				(width 0.1)
				(type default)
			)
			(layer "B.Fab")
		)
		(fp_line
			(start -0.2794 0.9906)
			(end -0.2794 -0.1016)
			(stroke
				(width 0.1)
				(type default)
			)
			(layer "B.Fab")
		)
		(pad "1" smd rect
			(at 0 0 270)
			(size 0.508 0.508)
			(layers "B.Cu" "B.Mask" "B.Paste")
			(net "VR_PVCCIN_CPU1_PH1_VCIN")
		)
		(pad "2" smd rect
			(at 0 0.889 270)
			(size 0.508 0.508)
			(layers "B.Cu" "B.Mask" "B.Paste")
			(net "P5V_STBY")
		)
		(zone
			(layer "B.Cu")
			(hatch none 0.5)
			(connect_pads
				(clearance 0)
			)
			(min_thickness 0.25)
			(keepout
				(tracks allowed)
				(vias not_allowed)
				(pads allowed)
				(copperpour not_allowed)
				(footprints allowed)
			)
			(placement
				(enabled no)
				(sheetname "")
			)
			(fill
				(thermal_gap 0.5)
				(thermal_bridge_width 0.5)
				(island_removal_mode 0)
			)
			(polygon
				(pts
					(xy 32.5882 -54.7624) (xy 32.5882 -54.2544) (xy 32.9692 -54.2544) (xy 32.9692 -54.7624)
				)
			)
		)
		(zone
			(layer "B.Cu")
			(hatch none 0.5)
			(connect_pads
				(clearance 0)
			)
			(min_thickness 0.25)
			(keepout
				(tracks not_allowed)
				(vias allowed)
				(pads allowed)
				(copperpour not_allowed)
				(footprints allowed)
			)
			(placement
				(enabled no)
				(sheetname "")
			)
			(fill
				(thermal_gap 0.5)
				(thermal_bridge_width 0.5)
				(island_removal_mode 0)
			)
			(polygon
				(pts
					(xy 32.9692 -54.7624) (xy 32.9692 -54.2544) (xy 32.5882 -54.2544) (xy 32.5882 -54.7624)
				)
			)
		)
	)
	(footprint ""
		(layer "B.Cu")
		(at 179.2986 -95.4532)
		(property "Reference" "C6N5"
			(at 3.17373 4.6482 270)
			(unlocked yes)
			(layer "B.SilkS")
			(effects
				(font
					(size 0.7874 0.5842)
					(thickness 0.1524)
				)
				(justify mirror)
			)
		)
		(property "Value" ""
			(at 0 0 0)
			(layer "B.Fab")
			(effects
				(font
					(size 1.27 1.27)
				)
				(justify mirror)
			)
		)
		(duplicate_pad_numbers_are_jumpers no)
		(fp_line
			(start -2.504948 -1.616456)
			(end -2.504948 1.633728)
			(stroke
				(width 0.1524)
				(type default)
			)
			(layer "B.SilkS")
		)
		(fp_line
			(start -2.504948 1.633728)
			(end -1.6002 1.633728)
			(stroke
				(width 0.1524)
				(type default)
			)
			(layer "B.SilkS")
		)
		(fp_line
			(start -2.286 7.366)
			(end -2.286 1.63195)
			(stroke
				(width 0.1524)
				(type default)
			)
			(layer "B.SilkS")
		)
		(fp_line
			(start -2.286 7.366)
			(end -1.600708 7.366)
			(stroke
				(width 0.1524)
				(type default)
			)
			(layer "B.SilkS")
		)
		(fp_line
			(start -1.6002 -1.616456)
			(end -2.504948 -1.616456)
			(stroke
				(width 0.1524)
				(type default)
			)
			(layer "B.SilkS")
		)
		(fp_line
			(start 1.6002 -1.616456)
			(end 2.563114 -1.616456)
			(stroke
				(width 0.1524)
				(type default)
			)
			(layer "B.SilkS")
		)
		(fp_line
			(start 2.286 7.366)
			(end 1.60147 7.366)
			(stroke
				(width 0.1524)
				(type default)
			)
			(layer "B.SilkS")
		)
		(fp_line
			(start 2.286 7.366)
			(end 2.286 1.632712)
			(stroke
				(width 0.1524)
				(type default)
			)
			(layer "B.SilkS")
		)
		(fp_line
			(start 2.563114 -1.616456)
			(end 2.563114 1.633728)
			(stroke
				(width 0.1524)
				(type default)
			)
			(layer "B.SilkS")
		)
		(fp_line
			(start 2.563114 1.633728)
			(end 1.6002 1.633728)
			(stroke
				(width 0.1524)
				(type default)
			)
			(layer "B.SilkS")
		)
		(fp_rect
			(start 2.286 7.366)
			(end -2.286 -0.254)
			(stroke
				(width 0)
				(type default)
			)
			(fill no)
			(layer "B.CrtYd")
		)
		(fp_line
			(start -2.286 -0.254)
			(end -2.286 7.366)
			(stroke
				(width 0.1)
				(type default)
			)
			(layer "B.Fab")
		)
		(fp_line
			(start -2.286 7.366)
			(end 2.286 7.366)
			(stroke
				(width 0.1)
				(type default)
			)
			(layer "B.Fab")
		)
		(fp_line
			(start 2.286 -0.254)
			(end -2.286 -0.254)
			(stroke
				(width 0.1)
				(type default)
			)
			(layer "B.Fab")
		)
		(fp_line
			(start 2.286 7.366)
			(end 2.286 -0.254)
			(stroke
				(width 0.1)
				(type default)
			)
			(layer "B.Fab")
		)
		(pad "1" smd rect
			(at 0 0 180)
			(size 2.54 3.048)
			(layers "B.Cu" "B.Mask" "B.Paste")
			(net "P12V_STBY")
		)
		(pad "2" smd rect
			(at 0 7.112 180)
			(size 2.54 3.048)
			(layers "B.Cu" "B.Mask" "B.Paste")
			(net "GND")
		)
	)
	(footprint ""
		(layer "B.Cu")
		(at 380.746 -46.0883 180)
		(property "Reference" "Q7E6"
			(at 1.17475 1.7907 90)
			(unlocked yes)
			(layer "B.SilkS")
			(effects
				(font
					(size 0.7874 0.5842)
					(thickness 0.1524)
				)
				(justify left mirror)
			)
		)
		(property "Value" ""
			(at 0 0 0)
			(layer "B.Fab")
			(effects
				(font
					(size 1.27 1.27)
				)
				(justify mirror)
			)
		)
		(duplicate_pad_numbers_are_jumpers no)
		(fp_circle
			(center 0.508 -0.7874)
			(end 0.381 -0.7874)
			(stroke
				(width 0.254)
				(type default)
			)
			(fill no)
			(layer "B.SilkS")
		)
		(fp_poly
			(pts
				(xy -0.2159 1.7526) (xy -1.5621 1.7526) (xy -1.5621 -0.4572) (xy -0.2159 -0.4572)
			)
			(stroke
				(width 0)
				(type default)
			)
			(fill no)
			(layer "B.CrtYd")
		)
		(fp_line
			(start -0.2159 1.75514)
			(end -1.5621 1.75514)
			(stroke
				(width 0.1)
				(type default)
			)
			(layer "B.Fab")
		)
		(fp_line
			(start -0.2159 -0.45466)
			(end -0.2159 1.75514)
			(stroke
				(width 0.1)
				(type default)
			)
			(layer "B.Fab")
		)
		(fp_line
			(start -1.5621 1.75514)
			(end -1.5621 -0.45466)
			(stroke
				(width 0.1)
				(type default)
			)
			(layer "B.Fab")
		)
		(fp_line
			(start -1.5621 -0.45466)
			(end -0.2159 -0.45466)
			(stroke
				(width 0.1)
				(type default)
			)
			(layer "B.Fab")
		)
		(fp_circle
			(center 0.508 -0.7874)
			(end 0.381 -0.7874)
			(stroke
				(width 0.254)
				(type default)
			)
			(fill no)
			(layer "B.Fab")
		)
		(pad "1" smd rect
			(at 0 0)
			(size 1.016 0.381)
			(layers "B.Cu" "B.Mask" "B.Paste")
			(net "GND")
		)
		(pad "2" smd rect
			(at 0 0.65024)
			(size 1.016 0.381)
			(layers "B.Cu" "B.Mask" "B.Paste")
			(net "IRQ_CPU1_PROCHOT_G_N")
		)
		(pad "3" smd rect
			(at 0 1.30048)
			(size 1.016 0.381)
			(layers "B.Cu" "B.Mask" "B.Paste")
			(net "H_CPU1_PROCHOT_G_N")
		)
		(pad "4" smd rect
			(at -1.778 1.30048)
			(size 1.016 0.381)
			(layers "B.Cu" "B.Mask" "B.Paste")
			(net "GND")
		)
		(pad "5" smd rect
			(at -1.778 0.65024)
			(size 1.016 0.381)
			(layers "B.Cu" "B.Mask" "B.Paste")
			(net "IRQ_CPU1_VRHOT")
		)
		(pad "6" smd rect
			(at -1.778 0)
			(size 1.016 0.381)
			(layers "B.Cu" "B.Mask" "B.Paste")
			(net "IRQ_CPU1_VRHOT")
		)
		(zone
			(layer "B.Cu")
			(hatch none 0.5)
			(connect_pads
				(clearance 0)
			)
			(min_thickness 0.25)
			(keepout
				(tracks allowed)
				(vias not_allowed)
				(pads allowed)
				(copperpour not_allowed)
				(footprints allowed)
			)
			(placement
				(enabled no)
				(sheetname "")
			)
			(fill
				(thermal_gap 0.5)
				(thermal_bridge_width 0.5)
				(island_removal_mode 0)
			)
			(polygon
				(pts
					(xy 380.238 -45.8978) (xy 381.254 -45.8978) (xy 381.254 -47.5869) (xy 380.238 -47.5869)
				)
			)
		)
		(zone
			(layer "B.Cu")
			(hatch none 0.5)
			(connect_pads
				(clearance 0)
			)
			(min_thickness 0.25)
			(keepout
				(tracks allowed)
				(vias not_allowed)
				(pads allowed)
				(copperpour not_allowed)
				(footprints allowed)
			)
			(placement
				(enabled no)
				(sheetname "")
			)
			(fill
				(thermal_gap 0.5)
				(thermal_bridge_width 0.5)
				(island_removal_mode 0)
			)
			(polygon
				(pts
					(xy 382.016 -45.8978) (xy 383.032 -45.8978) (xy 383.032 -47.5869) (xy 382.016 -47.5869)
				)
			)
		)
	)
	(footprint ""
		(layer "B.Cu")
		(at 490.3851 -121.5136 90)
		(property "Reference" "R9G12"
			(at 0 0 90)
			(layer "B.SilkS")
			(hide yes)
			(effects
				(font
					(size 1.27 1.27)
				)
				(justify mirror)
			)
		)
		(property "Value" ""
			(at 0 0 90)
			(layer "B.Fab")
			(effects
				(font
					(size 1.27 1.27)
				)
				(justify mirror)
			)
		)
		(duplicate_pad_numbers_are_jumpers no)
		(fp_poly
			(pts
				(xy 0.2794 -0.1016) (xy -0.2794 -0.1016) (xy -0.2794 0.9906) (xy 0.2794 0.9906)
			)
			(stroke
				(width 0)
				(type default)
			)
			(fill no)
			(layer "B.CrtYd")
		)
		(fp_line
			(start 0.2794 -0.1016)
			(end 0.2794 0.9906)
			(stroke
				(width 0.1)
				(type default)
			)
			(layer "B.Fab")
		)
		(fp_line
			(start -0.2794 -0.1016)
			(end 0.2794 -0.1016)
			(stroke
				(width 0.1)
				(type default)
			)
			(layer "B.Fab")
		)
		(fp_line
			(start 0.2794 0.9906)
			(end -0.2794 0.9906)
			(stroke
				(width 0.1)
				(type default)
			)
			(layer "B.Fab")
		)
		(fp_line
			(start -0.2794 0.9906)
			(end -0.2794 -0.1016)
			(stroke
				(width 0.1)
				(type default)
			)
			(layer "B.Fab")
		)
		(pad "1" smd rect
			(at 0 0 270)
			(size 0.508 0.508)
			(layers "B.Cu" "B.Mask" "B.Paste")
			(net "SMB_OCP_LAN_STBY_LVC3_SDA")
		)
		(pad "2" smd rect
			(at 0 0.889 270)
			(size 0.508 0.508)
			(layers "B.Cu" "B.Mask" "B.Paste")
			(net "SMB_SPRINGVILLE_STBY_LVC3_SDA")
		)
		(zone
			(layer "B.Cu")
			(hatch none 0.5)
			(connect_pads
				(clearance 0)
			)
			(min_thickness 0.25)
			(keepout
				(tracks allowed)
				(vias not_allowed)
				(pads allowed)
				(copperpour not_allowed)
				(footprints allowed)
			)
			(placement
				(enabled no)
				(sheetname "")
			)
			(fill
				(thermal_gap 0.5)
				(thermal_bridge_width 0.5)
				(island_removal_mode 0)
			)
			(polygon
				(pts
					(xy 490.6391 -121.7676) (xy 490.6391 -121.2596) (xy 491.0201 -121.2596) (xy 491.0201 -121.7676)
				)
			)
		)
		(zone
			(layer "B.Cu")
			(hatch none 0.5)
			(connect_pads
				(clearance 0)
			)
			(min_thickness 0.25)
			(keepout
				(tracks not_allowed)
				(vias allowed)
				(pads allowed)
				(copperpour not_allowed)
				(footprints allowed)
			)
			(placement
				(enabled no)
				(sheetname "")
			)
			(fill
				(thermal_gap 0.5)
				(thermal_bridge_width 0.5)
				(island_removal_mode 0)
			)
			(polygon
				(pts
					(xy 491.0201 -121.7676) (xy 491.0201 -121.2596) (xy 490.6391 -121.2596) (xy 490.6391 -121.7676)
				)
			)
		)
	)
)
